# S9S_MB_2U (Grand Teton) — schematic netlist excerpt (pin names and nets, part order shuffled) for the footprints in the layout excerpt that follows; sources: Cadence DE-HDL packaged netlist, KiCad conversion of 03242023_DA0F0TMBIJ0_F0T_Motherboard_J_brd_V01_OCP.brd

C268  Q_CAP  10UF 6.3V 20% X6S  pkg C0402  page 77 : A = PVCCIN_CPU1 ; B = GND
PR2718  Q_RES  8.87K 1% EMPTY  pkg 0402LF  page 279 : A = PVCCD_HV_CPU0_LSET1 ; B = GND

(kicad_pcb
	(version 20260206)
	(generator "pcbnew")
	(generator_version "10.0")
	(general
		(thickness 1.6)
		(legacy_teardrops no)
	)
	(paper "A4")
	(title_block
		(title "03242023_DA0F0TMBIJ0_F0T_Motherboard_J_brd_V01_OCP.brd")
		(comment 1 "Grand Teton / footprints 3640-3641 of 6105")
	)
	(layers
		(0 "F.Cu" signal "TOP")
		(4 "In1.Cu" signal "GND")
		(6 "In2.Cu" signal "IN1")
		(8 "In3.Cu" signal "GND1")
		(10 "In4.Cu" signal "IN2")
		(12 "In5.Cu" signal "GND2")
		(14 "In6.Cu" signal "IN3")
		(16 "In7.Cu" signal "GND3")
		(18 "In8.Cu" signal "VCC")
		(20 "In9.Cu" signal "VCC1")
		(22 "In10.Cu" signal "GND4")
		(24 "In11.Cu" signal "IN4")
		(26 "In12.Cu" signal "GND5")
		(28 "In13.Cu" signal "IN5")
		(30 "In14.Cu" signal "GND6")
		(32 "In15.Cu" signal "IN6")
		(34 "In16.Cu" signal "GND7")
		(2 "B.Cu" signal "BOTTOM")
		(9 "F.Adhes" user "F.Adhesive")
		(11 "B.Adhes" user "B.Adhesive")
		(13 "F.Paste" user "Package Geometry/Pastemask Top")
		(15 "B.Paste" user "Package Geometry/Pastemask Bottom")
		(5 "F.SilkS" user "Ref Des/Silkscreen Top")
		(7 "B.SilkS" user "Ref Des/Silkscreen Bottom")
		(1 "F.Mask" user "Board Geometry/Soldermask Top")
		(3 "B.Mask" user "Board Geometry/Soldermask Bottom")
		(17 "Dwgs.User" user "User.Drawings")
		(19 "Cmts.User" user "User.Comments")
		(21 "Eco1.User" user "User.Eco1")
		(23 "Eco2.User" user "User.Eco2")
		(25 "Edge.Cuts" user "Board Geometry/Outline")
		(27 "Margin" user)
		(31 "F.CrtYd" user "Package Geometry/Place Bound Top")
		(29 "B.CrtYd" user "Package Geometry/Place Bound Bottom")
		(35 "F.Fab" user "Ref Des/Assembly Top")
		(33 "B.Fab" user "Ref Des/Assembly Bottom")
	)
	(footprint ""
		(layer "F.Cu")
		(at 421.15359 -163.477194 -90)
		(property "Reference" "PR2718"
			(at 0 0 270)
			(layer "F.SilkS")
			(hide yes)
			(effects
				(font
					(size 1.27 1.27)
				)
			)
		)
		(property "Value" ""
			(at 0 0 270)
			(layer "F.Fab")
			(effects
				(font
					(size 1.27 1.27)
				)
			)
		)
		(duplicate_pad_numbers_are_jumpers no)
		(fp_line
			(start -0.7874 0.4064)
			(end -0.7874 -0.4064)
			(stroke
				(width 0.1524)
				(type default)
			)
			(layer "F.SilkS")
		)
		(fp_line
			(start 0.7874 0.4064)
			(end -0.7874 0.4064)
			(stroke
				(width 0.1524)
				(type default)
			)
			(layer "F.SilkS")
		)
		(fp_line
			(start -0.7874 -0.4064)
			(end 0.7874 -0.4064)
			(stroke
				(width 0.1524)
				(type default)
			)
			(layer "F.SilkS")
		)
		(fp_line
			(start 0.7874 -0.4064)
			(end 0.7874 0.4064)
			(stroke
				(width 0.1524)
				(type default)
			)
			(layer "F.SilkS")
		)
		(fp_line
			(start -0.67945 0.3048)
			(end -0.67945 -0.305054)
			(stroke
				(width 0.1)
				(type default)
			)
			(layer "F.Fab")
		)
		(fp_line
			(start -0.12065 0.3048)
			(end -0.67945 0.3048)
			(stroke
				(width 0.1)
				(type default)
			)
			(layer "F.Fab")
		)
		(fp_line
			(start 0.120396 0.3048)
			(end 0.120396 0.2794)
			(stroke
				(width 0.1)
				(type default)
			)
			(layer "F.Fab")
		)
		(fp_line
			(start 0.67945 0.3048)
			(end 0.120396 0.3048)
			(stroke
				(width 0.1)
				(type default)
			)
			(layer "F.Fab")
		)
		(fp_line
			(start -0.12065 0.2794)
			(end -0.12065 0.3048)
			(stroke
				(width 0.1)
				(type default)
			)
			(layer "F.Fab")
		)
		(fp_line
			(start 0.120396 0.2794)
			(end -0.12065 0.2794)
			(stroke
				(width 0.1)
				(type default)
			)
			(layer "F.Fab")
		)
		(fp_line
			(start -0.12065 -0.2794)
			(end 0.12065 -0.2794)
			(stroke
				(width 0.1)
				(type default)
			)
			(layer "F.Fab")
		)
		(fp_line
			(start 0.12065 -0.2794)
			(end 0.12065 -0.3048)
			(stroke
				(width 0.1)
				(type default)
			)
			(layer "F.Fab")
		)
		(fp_line
			(start 0.12065 -0.3048)
			(end 0.67945 -0.3048)
			(stroke
				(width 0.1)
				(type default)
			)
			(layer "F.Fab")
		)
		(fp_line
			(start 0.67945 -0.3048)
			(end 0.67945 0.3048)
			(stroke
				(width 0.1)
				(type default)
			)
			(layer "F.Fab")
		)
		(fp_line
			(start -0.67945 -0.305054)
			(end -0.12065 -0.305054)
			(stroke
				(width 0.1)
				(type default)
			)
			(layer "F.Fab")
		)
		(fp_line
			(start -0.12065 -0.305054)
			(end -0.12065 -0.2794)
			(stroke
				(width 0.1)
				(type default)
			)
			(layer "F.Fab")
		)
		(pad "1" smd circle
			(at -0.40005 0 270)
			(size 0 0)
			(layers "F.Cu" "F.Mask" "F.Paste")
			(net "PVCCD_HV_CPU0_LSET1")
		)
		(pad "2" smd circle
			(at 0.40005 0 270)
			(size 0 0)
			(layers "F.Cu" "F.Mask" "F.Paste")
			(net "GND")
		)
	)
	(footprint ""
		(layer "F.Cu")
		(at 119.508016 -255.0541 90)
		(property "Reference" "C268"
			(at 0 0 90)
			(layer "F.SilkS")
			(hide yes)
			(effects
				(font
					(size 1.27 1.27)
				)
			)
		)
		(property "Value" ""
			(at 0 0 90)
			(layer "F.Fab")
			(effects
				(font
					(size 1.27 1.27)
				)
			)
		)
		(duplicate_pad_numbers_are_jumpers no)
		(fp_line
			(start 0.7874 -0.4064)
			(end 0.7874 0.4064)
			(stroke
				(width 0.1524)
				(type default)
			)
			(layer "F.SilkS")
		)
		(fp_line
			(start -0.7874 -0.4064)
			(end 0.7874 -0.4064)
			(stroke
				(width 0.1524)
				(type default)
			)
			(layer "F.SilkS")
		)
		(fp_line
			(start 0.7874 0.4064)
			(end -0.7874 0.4064)
			(stroke
				(width 0.1524)
				(type default)
			)
			(layer "F.SilkS")
		)
		(fp_line
			(start -0.7874 0.4064)
			(end -0.7874 -0.4064)
			(stroke
				(width 0.1524)
				(type default)
			)
			(layer "F.SilkS")
		)
		(fp_line
			(start -0.12065 -0.305054)
			(end -0.12065 -0.2794)
			(stroke
				(width 0.1)
				(type default)
			)
			(layer "F.Fab")
		)
		(fp_line
			(start -0.67945 -0.305054)
			(end -0.12065 -0.305054)
			(stroke
				(width 0.1)
				(type default)
			)
			(layer "F.Fab")
		)
		(fp_line
			(start 0.67945 -0.3048)
			(end 0.67945 0.3048)
			(stroke
				(width 0.1)
				(type default)
			)
			(layer "F.Fab")
		)
		(fp_line
			(start 0.12065 -0.3048)
			(end 0.67945 -0.3048)
			(stroke
				(width 0.1)
				(type default)
			)
			(layer "F.Fab")
		)
		(fp_line
			(start 0.12065 -0.2794)
			(end 0.12065 -0.3048)
			(stroke
				(width 0.1)
				(type default)
			)
			(layer "F.Fab")
		)
		(fp_line
			(start -0.12065 -0.2794)
			(end 0.12065 -0.2794)
			(stroke
				(width 0.1)
				(type default)
			)
			(layer "F.Fab")
		)
		(fp_line
			(start 0.120396 0.2794)
			(end -0.12065 0.2794)
			(stroke
				(width 0.1)
				(type default)
			)
			(layer "F.Fab")
		)
		(fp_line
			(start -0.12065 0.2794)
			(end -0.12065 0.3048)
			(stroke
				(width 0.1)
				(type default)
			)
			(layer "F.Fab")
		)
		(fp_line
			(start 0.67945 0.3048)
			(end 0.120396 0.3048)
			(stroke
				(width 0.1)
				(type default)
			)
			(layer "F.Fab")
		)
		(fp_line
			(start 0.120396 0.3048)
			(end 0.120396 0.2794)
			(stroke
				(width 0.1)
				(type default)
			)
			(layer "F.Fab")
		)
		(fp_line
			(start -0.12065 0.3048)
			(end -0.67945 0.3048)
			(stroke
				(width 0.1)
				(type default)
			)
			(layer "F.Fab")
		)
		(fp_line
			(start -0.67945 0.3048)
			(end -0.67945 -0.305054)
			(stroke
				(width 0.1)
				(type default)
			)
			(layer "F.Fab")
		)
		(pad "1" smd circle
			(at -0.40005 0 90)
			(size 0 0)
			(layers "F.Cu" "F.Mask" "F.Paste")
			(net "PVCCIN_CPU1")
		)
		(pad "2" smd circle
			(at 0.40005 0 90)
			(size 0 0)
			(layers "F.Cu" "F.Mask" "F.Paste")
			(net "GND")
		)
	)
)
